(kicad_pcb
	(version 20260206)
	(generator "pcbnew")
	(generator_version "10.0")
	(general
		(thickness 1.6)
		(legacy_teardrops no)
	)
	(paper "A4")
	(title_block
		(title "timecard-production-celestica-r4006 — R4006-B0001-02_R01.brd")
		(comment 1 "Time Appliance Project (Time Card) / footprints 784-788 of 1113")
	)
	(layers
		(0 "F.Cu" signal "TOP")
		(4 "In1.Cu" signal "L02_GND1")
		(6 "In2.Cu" signal "L03_SIG1")
		(8 "In3.Cu" signal "L04_GND2")
		(10 "In4.Cu" signal "L05_VCC1")
		(12 "In5.Cu" signal "L06_VCC2")
		(14 "In6.Cu" signal "L07_GND3")
		(16 "In7.Cu" signal "L08_SIG2")
		(18 "In8.Cu" signal "L09_GND4")
		(2 "B.Cu" signal "BOTTOM")
		(9 "F.Adhes" user "F.Adhesive")
		(11 "B.Adhes" user "B.Adhesive")
		(13 "F.Paste" user "Package Geometry/Pastemask Top")
		(15 "B.Paste" user "Package Geometry/Pastemask Bottom")
		(5 "F.SilkS" user "Ref Des/Silkscreen Top")
		(7 "B.SilkS" user "Ref Des/Silkscreen Bottom")
		(1 "F.Mask" user "Board Geometry/Soldermask Top")
		(3 "B.Mask" user "Board Geometry/Soldermask Bottom")
		(17 "Dwgs.User" user "User.Drawings")
		(19 "Cmts.User" user "User.Comments")
		(21 "Eco1.User" user "User.Eco1")
		(23 "Eco2.User" user "User.Eco2")
		(25 "Edge.Cuts" user "Board Geometry/Outline")
		(27 "Margin" user)
		(31 "F.CrtYd" user "Package Geometry/Place Bound Top")
		(29 "B.CrtYd" user "Package Geometry/Place Bound Bottom")
		(35 "F.Fab" user "Ref Des/Assembly Top")
		(33 "B.Fab" user "Ref Des/Assembly Bottom")
	)
	(footprint ""
		(layer "B.Cu")
		(at 124.587 -41.402)
		(property "Reference" "R217"
			(at 3.429 0.16637 0)
			(unlocked yes)
			(layer "B.SilkS")
			(effects
				(font
					(size 0.7874 0.5842)
					(thickness 0.1524)
				)
				(justify mirror)
			)
		)
		(property "Value" "VAL*"
			(at -0.02032 2.13233 0)
			(unlocked yes)
			(layer "B.Fab")
			(hide yes)
			(effects
				(font
					(size 0.7874 0.5842)
					(thickness 0.1524)
				)
				(justify mirror)
			)
		)
		(property "Tolerance" "TOL*"
			(at -0.044704 3.05435 0)
			(unlocked yes)
			(layer "Cmts.User")
			(hide yes)
			(effects
				(font
					(size 0.7874 0.5842)
					(thickness 0.1524)
				)
				(justify mirror)
			)
		)
		(property "User Part Number" "PARTNUM*"
			(at -0.02032 4.024884 0)
			(unlocked yes)
			(layer "Cmts.User")
			(hide yes)
			(effects
				(font
					(size 0.7874 0.5842)
					(thickness 0.1524)
				)
				(justify mirror)
			)
		)
		(property "Device Type" "RESISTOR-G155-11000-01,100OHM,A"
			(at -0.008382 1.210564 0)
			(unlocked yes)
			(layer "B.Fab")
			(hide yes)
			(effects
				(font
					(size 0.7874 0.5842)
					(thickness 0.1524)
				)
				(justify mirror)
			)
		)
		(duplicate_pad_numbers_are_jumpers no)
		(fp_line
			(start -1.143 -0.5588)
			(end 1.143 -0.5588)
			(stroke
				(width 0.1)
				(type default)
			)
			(layer "B.SilkS")
		)
		(fp_line
			(start -1.143 0.5588)
			(end -1.143 -0.5588)
			(stroke
				(width 0.1)
				(type default)
			)
			(layer "B.SilkS")
		)
		(fp_line
			(start 1.143 -0.5588)
			(end 1.143 0.5588)
			(stroke
				(width 0.1)
				(type default)
			)
			(layer "B.SilkS")
		)
		(fp_line
			(start 1.143 0.5588)
			(end -1.143 0.5588)
			(stroke
				(width 0.1)
				(type default)
			)
			(layer "B.SilkS")
		)
		(fp_rect
			(start -1.143 0.5588)
			(end 1.143 -0.5588)
			(stroke
				(width 0)
				(type default)
			)
			(fill no)
			(layer "B.CrtYd")
		)
		(fp_line
			(start -0.508 -0.3048)
			(end 0.508 -0.3048)
			(stroke
				(width 0.1)
				(type default)
			)
			(layer "B.Fab")
		)
		(fp_line
			(start -0.508 0.3048)
			(end -0.508 -0.3048)
			(stroke
				(width 0.1)
				(type default)
			)
			(layer "B.Fab")
		)
		(fp_line
			(start 0.508 -0.3048)
			(end 0.508 0.3048)
			(stroke
				(width 0.1)
				(type default)
			)
			(layer "B.Fab")
		)
		(fp_line
			(start 0.508 0.3048)
			(end -0.508 0.3048)
			(stroke
				(width 0.1)
				(type default)
			)
			(layer "B.Fab")
		)
		(pad "1" smd rect
			(at 0.5334 0 180)
			(size 0.7112 0.6096)
			(layers "B.Cu" "B.Mask" "B.Paste")
			(net "XP3R3V_FPGA")
		)
		(pad "2" smd rect
			(at -0.5334 0 180)
			(size 0.7112 0.6096)
			(layers "B.Cu" "B.Mask" "B.Paste")
			(net "FPGA_M1")
		)
		(zone
			(layer "B.Cu")
			(hatch none 0.5)
			(connect_pads
				(clearance 0)
			)
			(min_thickness 0.25)
			(keepout
				(tracks allowed)
				(vias not_allowed)
				(pads allowed)
				(copperpour not_allowed)
				(footprints allowed)
			)
			(placement
				(enabled no)
				(sheetname "")
			)
			(fill
				(thermal_gap 0.5)
				(thermal_bridge_width 0.5)
				(island_removal_mode 0)
			)
			(polygon
				(pts
					(xy 124.5108 -41.0972) (xy 124.6632 -41.0972) (xy 124.6632 -41.7068) (xy 124.5108 -41.7068)
				)
			)
		)
	)
	(footprint ""
		(layer "B.Cu")
		(at 117.729 -98.933)
		(property "Reference" "C80"
			(at -1.016 1.30937 0)
			(unlocked yes)
			(layer "B.SilkS")
			(effects
				(font
					(size 0.7874 0.5842)
					(thickness 0.1524)
				)
				(justify mirror)
			)
		)
		(property "Value" "VAL*"
			(at -0.0762 2.067306 0)
			(unlocked yes)
			(layer "B.Fab")
			(hide yes)
			(effects
				(font
					(size 0.7874 0.5842)
					(thickness 0.1524)
				)
				(justify mirror)
			)
		)
		(property "Tolerance" "TOL*"
			(at -0.0762 3.032506 0)
			(unlocked yes)
			(layer "Cmts.User")
			(hide yes)
			(effects
				(font
					(size 0.7874 0.5842)
					(thickness 0.1524)
				)
				(justify mirror)
			)
		)
		(property "User Part Number" "PARTNUM*"
			(at -0.1016 4.023106 0)
			(unlocked yes)
			(layer "Cmts.User")
			(hide yes)
			(effects
				(font
					(size 0.7874 0.5842)
					(thickness 0.1524)
				)
				(justify mirror)
			)
		)
		(property "Device Type" "CAPACITOR-G105-0B104-CK,0.1UF,A"
			(at -0.0508 1.127506 0)
			(unlocked yes)
			(layer "B.Fab")
			(hide yes)
			(effects
				(font
					(size 0.7874 0.5842)
					(thickness 0.1524)
				)
				(justify mirror)
			)
		)
		(duplicate_pad_numbers_are_jumpers no)
		(fp_line
			(start -1.143 -0.5588)
			(end 1.143 -0.5588)
			(stroke
				(width 0.1)
				(type default)
			)
			(layer "B.SilkS")
		)
		(fp_line
			(start -1.143 0.5588)
			(end -1.143 -0.5588)
			(stroke
				(width 0.1)
				(type default)
			)
			(layer "B.SilkS")
		)
		(fp_line
			(start 1.143 -0.5588)
			(end 1.143 0.5588)
			(stroke
				(width 0.1)
				(type default)
			)
			(layer "B.SilkS")
		)
		(fp_line
			(start 1.143 0.5588)
			(end -1.143 0.5588)
			(stroke
				(width 0.1)
				(type default)
			)
			(layer "B.SilkS")
		)
		(fp_rect
			(start -1.143 -0.5588)
			(end 1.143 0.5588)
			(stroke
				(width 0)
				(type default)
			)
			(fill no)
			(layer "B.CrtYd")
		)
		(fp_line
			(start -0.508 -0.3048)
			(end 0.508 -0.3048)
			(stroke
				(width 0.1)
				(type default)
			)
			(layer "B.Fab")
		)
		(fp_line
			(start -0.508 0.3048)
			(end -0.508 -0.3048)
			(stroke
				(width 0.1)
				(type default)
			)
			(layer "B.Fab")
		)
		(fp_line
			(start 0.508 -0.3048)
			(end 0.508 0.3048)
			(stroke
				(width 0.1)
				(type default)
			)
			(layer "B.Fab")
		)
		(fp_line
			(start 0.508 0.3048)
			(end -0.508 0.3048)
			(stroke
				(width 0.1)
				(type default)
			)
			(layer "B.Fab")
		)
		(pad "1" smd rect
			(at 0.5334 0 180)
			(size 0.7112 0.6096)
			(layers "B.Cu" "B.Mask" "B.Paste")
			(net "XP3R3V_GPS")
		)
		(pad "2" smd rect
			(at -0.5334 0 180)
			(size 0.7112 0.6096)
			(layers "B.Cu" "B.Mask" "B.Paste")
			(net "SG")
		)
		(zone
			(layer "B.Cu")
			(hatch none 0.5)
			(connect_pads
				(clearance 0)
			)
			(min_thickness 0.25)
			(keepout
				(tracks allowed)
				(vias not_allowed)
				(pads allowed)
				(copperpour not_allowed)
				(footprints allowed)
			)
			(placement
				(enabled no)
				(sheetname "")
			)
			(fill
				(thermal_gap 0.5)
				(thermal_bridge_width 0.5)
				(island_removal_mode 0)
			)
			(polygon
				(pts
					(xy 117.6528 -99.2378) (xy 117.6528 -98.6282) (xy 117.8052 -98.6282) (xy 117.8052 -99.2378)
				)
			)
		)
	)
	(footprint ""
		(layer "B.Cu")
		(at 147.066 -103.505)
		(property "Reference" "R262"
			(at 1.016 3.08737 0)
			(unlocked yes)
			(layer "B.SilkS")
			(effects
				(font
					(size 0.7874 0.5842)
					(thickness 0.1524)
				)
				(justify mirror)
			)
		)
		(property "Value" "VAL*"
			(at -0.02032 2.13233 0)
			(unlocked yes)
			(layer "B.Fab")
			(hide yes)
			(effects
				(font
					(size 0.7874 0.5842)
					(thickness 0.1524)
				)
				(justify mirror)
			)
		)
		(property "Tolerance" "TOL*"
			(at -0.044704 3.05435 0)
			(unlocked yes)
			(layer "Cmts.User")
			(hide yes)
			(effects
				(font
					(size 0.7874 0.5842)
					(thickness 0.1524)
				)
				(justify mirror)
			)
		)
		(property "User Part Number" "PARTNUM*"
			(at -0.02032 4.024884 0)
			(unlocked yes)
			(layer "Cmts.User")
			(hide yes)
			(effects
				(font
					(size 0.7874 0.5842)
					(thickness 0.1524)
				)
				(justify mirror)
			)
		)
		(property "Device Type" "RESISTOR-G155-11001-01,1KOHM,1%"
			(at -0.008382 1.210564 0)
			(unlocked yes)
			(layer "B.Fab")
			(hide yes)
			(effects
				(font
					(size 0.7874 0.5842)
					(thickness 0.1524)
				)
				(justify mirror)
			)
		)
		(duplicate_pad_numbers_are_jumpers no)
		(fp_line
			(start -1.143 -0.5588)
			(end 1.143 -0.5588)
			(stroke
				(width 0.1)
				(type default)
			)
			(layer "B.SilkS")
		)
		(fp_line
			(start -1.143 0.5588)
			(end -1.143 -0.5588)
			(stroke
				(width 0.1)
				(type default)
			)
			(layer "B.SilkS")
		)
		(fp_line
			(start 1.143 -0.5588)
			(end 1.143 0.5588)
			(stroke
				(width 0.1)
				(type default)
			)
			(layer "B.SilkS")
		)
		(fp_line
			(start 1.143 0.5588)
			(end -1.143 0.5588)
			(stroke
				(width 0.1)
				(type default)
			)
			(layer "B.SilkS")
		)
		(fp_rect
			(start 1.143 0.5588)
			(end -1.143 -0.5588)
			(stroke
				(width 0)
				(type default)
			)
			(fill no)
			(layer "B.CrtYd")
		)
		(fp_line
			(start -0.508 -0.3048)
			(end 0.508 -0.3048)
			(stroke
				(width 0.1)
				(type default)
			)
			(layer "B.Fab")
		)
		(fp_line
			(start -0.508 0.3048)
			(end -0.508 -0.3048)
			(stroke
				(width 0.1)
				(type default)
			)
			(layer "B.Fab")
		)
		(fp_line
			(start 0.508 -0.3048)
			(end 0.508 0.3048)
			(stroke
				(width 0.1)
				(type default)
			)
			(layer "B.Fab")
		)
		(fp_line
			(start 0.508 0.3048)
			(end -0.508 0.3048)
			(stroke
				(width 0.1)
				(type default)
			)
			(layer "B.Fab")
		)
		(pad "1" smd rect
			(at 0.5334 0 180)
			(size 0.7112 0.6096)
			(layers "B.Cu" "B.Mask" "B.Paste")
			(net "UNNAMED_14_RESISTOR_I65_2")
		)
		(pad "2" smd rect
			(at -0.5334 0 180)
			(size 0.7112 0.6096)
			(layers "B.Cu" "B.Mask" "B.Paste")
			(net "XP12R0V")
		)
		(zone
			(layer "B.Cu")
			(hatch none 0.5)
			(connect_pads
				(clearance 0)
			)
			(min_thickness 0.25)
			(keepout
				(tracks allowed)
				(vias not_allowed)
				(pads allowed)
				(copperpour not_allowed)
				(footprints allowed)
			)
			(placement
				(enabled no)
				(sheetname "")
			)
			(fill
				(thermal_gap 0.5)
				(thermal_bridge_width 0.5)
				(island_removal_mode 0)
			)
			(polygon
				(pts
					(xy 147.1422 -103.2002) (xy 147.1422 -103.8098) (xy 146.9898 -103.8098) (xy 146.9898 -103.2002)
				)
			)
		)
	)
	(footprint ""
		(layer "B.Cu")
		(at 126.0094 -68.7578 -90)
		(property "Reference" "R174"
			(at 1.7018 1.33477 270)
			(unlocked yes)
			(layer "B.SilkS")
			(effects
				(font
					(size 0.7874 0.5842)
					(thickness 0.1524)
				)
				(justify mirror)
			)
		)
		(property "Value" "VAL*"
			(at -0.02032 2.13233 270)
			(unlocked yes)
			(layer "B.Fab")
			(hide yes)
			(effects
				(font
					(size 0.7874 0.5842)
					(thickness 0.1524)
				)
				(justify mirror)
			)
		)
		(property "Tolerance" "TOL*"
			(at -0.044704 3.05435 270)
			(unlocked yes)
			(layer "Cmts.User")
			(hide yes)
			(effects
				(font
					(size 0.7874 0.5842)
					(thickness 0.1524)
				)
				(justify mirror)
			)
		)
		(property "User Part Number" "PARTNUM*"
			(at -0.02032 4.024884 270)
			(unlocked yes)
			(layer "Cmts.User")
			(hide yes)
			(effects
				(font
					(size 0.7874 0.5842)
					(thickness 0.1524)
				)
				(justify mirror)
			)
		)
		(property "Device Type" "RESISTOR-G155-11002-01,10KOHM,A"
			(at -0.008382 1.210564 270)
			(unlocked yes)
			(layer "B.Fab")
			(hide yes)
			(effects
				(font
					(size 0.7874 0.5842)
					(thickness 0.1524)
				)
				(justify mirror)
			)
		)
		(duplicate_pad_numbers_are_jumpers no)
		(fp_line
			(start -1.143 0.5588)
			(end -1.143 -0.5588)
			(stroke
				(width 0.1)
				(type default)
			)
			(layer "B.SilkS")
		)
		(fp_line
			(start 1.143 0.5588)
			(end -1.143 0.5588)
			(stroke
				(width 0.1)
				(type default)
			)
			(layer "B.SilkS")
		)
		(fp_line
			(start -1.143 -0.5588)
			(end 1.143 -0.5588)
			(stroke
				(width 0.1)
				(type default)
			)
			(layer "B.SilkS")
		)
		(fp_line
			(start 1.143 -0.5588)
			(end 1.143 0.5588)
			(stroke
				(width 0.1)
				(type default)
			)
			(layer "B.SilkS")
		)
		(fp_rect
			(start -1.143 -0.5588)
			(end 1.143 0.5588)
			(stroke
				(width 0)
				(type default)
			)
			(fill no)
			(layer "B.CrtYd")
		)
		(fp_line
			(start -0.508 0.3048)
			(end -0.508 -0.3048)
			(stroke
				(width 0.1)
				(type default)
			)
			(layer "B.Fab")
		)
		(fp_line
			(start 0.508 0.3048)
			(end -0.508 0.3048)
			(stroke
				(width 0.1)
				(type default)
			)
			(layer "B.Fab")
		)
		(fp_line
			(start -0.508 -0.3048)
			(end 0.508 -0.3048)
			(stroke
				(width 0.1)
				(type default)
			)
			(layer "B.Fab")
		)
		(fp_line
			(start 0.508 -0.3048)
			(end 0.508 0.3048)
			(stroke
				(width 0.1)
				(type default)
			)
			(layer "B.Fab")
		)
		(pad "1" smd rect
			(at 0.5334 0 90)
			(size 0.7112 0.6096)
			(layers "B.Cu" "B.Mask" "B.Paste")
			(net "XP1R8V_EN_R")
		)
		(pad "2" smd rect
			(at -0.5334 0 90)
			(size 0.7112 0.6096)
			(layers "B.Cu" "B.Mask" "B.Paste")
			(net "SG")
		)
		(zone
			(layer "B.Cu")
			(hatch none 0.5)
			(connect_pads
				(clearance 0)
			)
			(min_thickness 0.25)
			(keepout
				(tracks allowed)
				(vias not_allowed)
				(pads allowed)
				(copperpour not_allowed)
				(footprints allowed)
			)
			(placement
				(enabled no)
				(sheetname "")
			)
			(fill
				(thermal_gap 0.5)
				(thermal_bridge_width 0.5)
				(island_removal_mode 0)
			)
			(polygon
				(pts
					(xy 126.3142 -68.834) (xy 125.7046 -68.834) (xy 125.7046 -68.6816) (xy 126.3142 -68.6816)
				)
			)
		)
	)
	(footprint ""
		(layer "B.Cu")
		(at 124.587 -44.831 180)
		(property "Reference" "R209"
			(at -3.683 -0.16637 0)
			(unlocked yes)
			(layer "B.SilkS")
			(effects
				(font
					(size 0.7874 0.5842)
					(thickness 0.1524)
				)
				(justify mirror)
			)
		)
		(property "Value" "VAL*"
			(at -0.02032 2.13233 180)
			(unlocked yes)
			(layer "B.Fab")
			(hide yes)
			(effects
				(font
					(size 0.7874 0.5842)
					(thickness 0.1524)
				)
				(justify mirror)
			)
		)
		(property "Device Type" "RESISTOR-G155-14701-01,4.7KOHMA"
			(at -0.008382 1.210564 180)
			(unlocked yes)
			(layer "B.Fab")
			(hide yes)
			(effects
				(font
					(size 0.7874 0.5842)
					(thickness 0.1524)
				)
				(justify mirror)
			)
		)
		(property "User Part Number" "PARTNUM*"
			(at -0.02032 4.024884 180)
			(unlocked yes)
			(layer "Cmts.User")
			(hide yes)
			(effects
				(font
					(size 0.7874 0.5842)
					(thickness 0.1524)
				)
				(justify mirror)
			)
		)
		(property "Tolerance" "TOL*"
			(at -0.044704 3.05435 180)
			(unlocked yes)
			(layer "Cmts.User")
			(hide yes)
			(effects
				(font
					(size 0.7874 0.5842)
					(thickness 0.1524)
				)
				(justify mirror)
			)
		)
		(duplicate_pad_numbers_are_jumpers no)
		(fp_line
			(start 1.143 0.5588)
			(end -1.143 0.5588)
			(stroke
				(width 0.1)
				(type default)
			)
			(layer "B.SilkS")
		)
		(fp_line
			(start 1.143 -0.5588)
			(end 1.143 0.5588)
			(stroke
				(width 0.1)
				(type default)
			)
			(layer "B.SilkS")
		)
		(fp_line
			(start -1.143 0.5588)
			(end -1.143 -0.5588)
			(stroke
				(width 0.1)
				(type default)
			)
			(layer "B.SilkS")
		)
		(fp_line
			(start -1.143 -0.5588)
			(end 1.143 -0.5588)
			(stroke
				(width 0.1)
				(type default)
			)
			(layer "B.SilkS")
		)
		(fp_rect
			(start -1.143 0.5588)
			(end 1.143 -0.5588)
			(stroke
				(width 0)
				(type default)
			)
			(fill no)
			(layer "B.CrtYd")
		)
		(fp_line
			(start 0.508 0.3048)
			(end -0.508 0.3048)
			(stroke
				(width 0.1)
				(type default)
			)
			(layer "B.Fab")
		)
		(fp_line
			(start 0.508 -0.3048)
			(end 0.508 0.3048)
			(stroke
				(width 0.1)
				(type default)
			)
			(layer "B.Fab")
		)
		(fp_line
			(start -0.508 0.3048)
			(end -0.508 -0.3048)
			(stroke
				(width 0.1)
				(type default)
			)
			(layer "B.Fab")
		)
		(fp_line
			(start -0.508 -0.3048)
			(end 0.508 -0.3048)
			(stroke
				(width 0.1)
				(type default)
			)
			(layer "B.Fab")
		)
		(pad "1" smd rect
			(at 0.5334 0)
			(size 0.7112 0.6096)
			(layers "B.Cu" "B.Mask" "B.Paste")
			(net "FPGA_CFG_INIT_N")
		)
		(pad "2" smd rect
			(at -0.5334 0)
			(size 0.7112 0.6096)
			(layers "B.Cu" "B.Mask" "B.Paste")
			(net "XP3R3V_FPGA")
		)
		(zone
			(layer "B.Cu")
			(hatch none 0.5)
			(connect_pads
				(clearance 0)
			)
			(min_thickness 0.25)
			(keepout
				(tracks allowed)
				(vias not_allowed)
				(pads allowed)
				(copperpour not_allowed)
				(footprints allowed)
			)
			(placement
				(enabled no)
				(sheetname "")
			)
			(fill
				(thermal_gap 0.5)
				(thermal_bridge_width 0.5)
				(island_removal_mode 0)
			)
			(polygon
				(pts
					(xy 124.6632 -45.1358) (xy 124.5108 -45.1358) (xy 124.5108 -44.5262) (xy 124.6632 -44.5262)
				)
			)
		)
	)
)
